(kicad_pcb
	(version 20221018)
	(generator pcbnew)
	(general
    (thickness 1.562)
  )
	(paper "A4")
	(title_block
    (title "Thunderbolt PCIe Adaper")
    (date "2024-07-09")
    (rev "1.0.3")
    (comment 1 "www.antmicro.com")
    (comment 2 "Antmicro Ltd.")
		(comment 9 "footprints 34-38 of 271")
	)
	(layers
    (0 "F.Cu" signal)
    (1 "In1.Cu" signal)
    (2 "In2.Cu" signal)
    (3 "In3.Cu" signal)
    (4 "In4.Cu" signal)
    (31 "B.Cu" signal)
    (32 "B.Adhes" user "B.Adhesive")
    (33 "F.Adhes" user "F.Adhesive")
    (34 "B.Paste" user)
    (35 "F.Paste" user)
    (36 "B.SilkS" user "B.Silkscreen")
    (37 "F.SilkS" user "F.Silkscreen")
    (38 "B.Mask" user)
    (39 "F.Mask" user)
    (40 "Dwgs.User" user "User.Drawings")
    (41 "Cmts.User" user "User.Comments")
    (42 "Eco1.User" user "User.Eco1")
    (43 "Eco2.User" user "User.Eco2")
    (44 "Edge.Cuts" user)
    (45 "Margin" user)
    (46 "B.CrtYd" user "B.Courtyard")
    (47 "F.CrtYd" user "F.Courtyard")
    (48 "B.Fab" user)
    (49 "F.Fab" user)
  )
	(footprint "antmicro-footprints:FB_0805_2012Metric" (layer "F.Cu")
    (at 107.091001 60.489)
    (descr "FERRITE BEAD 0805")
    (tags "FERRITE BEAD 0805")
    (property "Author" "Antmicro")
    (property "Current" "")
    (property "License" "Apache-2.0")
    (property "MPN" "BLM21SN300SZ1D")
    (property "Manufacturer" "Murata")
    (property "Sheetfile" "power.kicad_sch")
    (property "Sheetname" "Power")
    (property "Val" "30Z/8.5A")
    (property "ki_description" "Ferrite Bead, 0805 [2012 Metric], 30 ohm, 8.5 A, BLM21SN, 0.004 ohm, ± 10ohm, DC power line")
    (property "ki_keywords" "0805, SMT, FERRITE BEAD, PASSIVE")
    (attr smd)
    (fp_text reference "FB2" (at -1.173001 -1.053) (layer "F.SilkS")
        (effects (font (size 0.7 0.7) (thickness 0.15)) (justify left bottom))
    )
    (fp_text value "FB_30Z_8.5A_Murata-BLM21SN_0805" (at 0.001 1.801) (layer "F.Fab")
        (effects (font (size 0.7 0.7) (thickness 0.15)) (justify left bottom))
    )
    (fp_text user "Author: Antmicro" (at -1.44 5.001) (layer "F.Fab") hide
        (effects (font (size 0.7 0.7) (thickness 0.15)) (justify left bottom))
    )
    (fp_text user "${REFERENCE}" (at -1.44 3.801) (layer "F.Fab") hide
        (effects (font (size 0.7 0.7) (thickness 0.15)) (justify left bottom))
    )
    (fp_text user "License: Apache-2.0" (at -1.44 6.201) (layer "F.Fab") hide
        (effects (font (size 0.7 0.7) (thickness 0.15)) (justify left bottom))
    )
    (fp_line (start -0.319 0.698) (end 0.281 0.698)
      (stroke (width 0.15) (type solid)) (layer "F.SilkS"))
    (fp_line (start -0.299 -0.698) (end 0.299 -0.698)
      (stroke (width 0.15) (type solid)) (layer "F.SilkS"))
    (fp_rect (start 1.95 -0.9) (end -1.95 0.9)
      (stroke (width 0.05) (type default)) (fill none) (layer "F.CrtYd"))
    (fp_line (start -0.948 -0.681) (end 0.948 -0.681)
      (stroke (width 0.15) (type solid)) (layer "F.Fab"))
    (fp_line (start -0.948 -0.676) (end -0.948 0.676)
      (stroke (width 0.15) (type solid)) (layer "F.Fab"))
    (fp_line (start -0.948 0.681) (end 0.948 0.681)
      (stroke (width 0.15) (type solid)) (layer "F.Fab"))
    (fp_line (start 0.948 -0.676) (end 0.948 0.676)
      (stroke (width 0.15) (type solid)) (layer "F.Fab"))
    (pad "1" smd roundrect (at -1.1 0) (size 1.2 1.3) (layers "F.Cu" "F.Paste" "F.Mask") (roundrect_rratio 0.25)
      (net 3 "5V0_USB") (pintype "passive"))
    (pad "2" smd roundrect (at 1.1 0) (size 1.2 1.3) (layers "F.Cu" "F.Paste" "F.Mask") (roundrect_rratio 0.25)
      (net 90 "Net-(U2-VIN)") (pintype "passive"))
  )
	(footprint "antmicro-footprints:SOT-323" (layer "F.Cu")
    (at 103.035 87.975 90)
    (property "Author" "Antmicro")
    (property "License" "Apache-2.0")
    (property "MPN" "BC817-25W,115")
    (property "Manufacturer" "Nexperia")
    (property "Sheetfile" "power.kicad_sch")
    (property "Sheetname" "Power")
    (property "ki_description" "Bipolar (BJT) Single Transistor, NPN, 45 V, 500 mA, 200 mW, SOT-323, Surface Mount")
    (property "ki_keywords" "SMT, TRANSISTOR, SEMICONDUCTOR, BIPOLAR")
    (attr smd)
    (fp_text reference "Q2" (at -0.798 -1.562 90) (layer "F.SilkS")
        (effects (font (size 0.7 0.7) (thickness 0.15)) (justify left bottom))
    )
    (fp_text value "BC817-25W" (at 0 2.749 90) (layer "F.Fab")
        (effects (font (size 0.7 0.7) (thickness 0.15)) (justify left bottom))
    )
    (fp_text user "${REFERENCE}" (at -1.35 4.749 90) (layer "F.Fab") hide
        (effects (font (size 0.7 0.7) (thickness 0.15)) (justify left bottom))
    )
    (fp_text user "Author: Antmicro" (at -1.35 7.149 90) (layer "F.Fab") hide
        (effects (font (size 0.7 0.7) (thickness 0.15)) (justify left bottom))
    )
    (fp_text user "License: Apache-2.0" (at -1.35 5.949 90) (layer "F.Fab") hide
        (effects (font (size 0.7 0.7) (thickness 0.15)) (justify left bottom))
    )
    (fp_line (start -0.802 -1.2) (end -0.802 -1.05)
      (stroke (width 0.15) (type solid)) (layer "F.SilkS"))
    (fp_line (start -0.802 1.05) (end -0.802 1.199)
      (stroke (width 0.15) (type solid)) (layer "F.SilkS"))
    (fp_line (start -0.802 1.199) (end -0.5 1.199)
      (stroke (width 0.15) (type solid)) (layer "F.SilkS"))
    (fp_line (start -0.402 -1.2) (end -0.802 -1.2)
      (stroke (width 0.15) (type solid)) (layer "F.SilkS"))
    (fp_line (start 0.498 -1.2) (end 0.8 -1.2)
      (stroke (width 0.15) (type solid)) (layer "F.SilkS"))
    (fp_line (start 0.498 1.199) (end 0.8 1.199)
      (stroke (width 0.15) (type solid)) (layer "F.SilkS"))
    (fp_line (start 0.8 -1.2) (end 0.8 -0.902)
      (stroke (width 0.15) (type solid)) (layer "F.SilkS"))
    (fp_line (start 0.8 1.199) (end 0.8 0.9)
      (stroke (width 0.15) (type solid)) (layer "F.SilkS"))
    (fp_circle (center -1.05 -1.156824) (end -1 -1.129824)
      (stroke (width 0.15) (type solid)) (fill none) (layer "F.SilkS"))
    (fp_rect (start -1.35 -1.35) (end 1.35 1.35)
      (stroke (width 0.05) (type solid)) (fill none) (layer "F.CrtYd"))
    (fp_line (start -0.677 -1.101) (end -0.677 1.1)
      (stroke (width 0.15) (type solid)) (layer "F.Fab"))
    (fp_line (start -0.677 -1.101) (end 0.675 -1.101)
      (stroke (width 0.15) (type solid)) (layer "F.Fab"))
    (fp_line (start -0.677 1.1) (end 0.675 1.1)
      (stroke (width 0.15) (type solid)) (layer "F.Fab"))
    (fp_line (start 0.675 -1.101) (end 0.675 1.1)
      (stroke (width 0.15) (type solid)) (layer "F.Fab"))
    (pad "1" smd rect (at -0.927 -0.652 90) (size 0.55 0.6) (layers "F.Cu" "F.Paste" "F.Mask")
      (net 140 "Net-(Q2-B)") (pinfunction "B") (pintype "input"))
    (pad "2" smd rect (at -0.927 0.65 90) (size 0.55 0.6) (layers "F.Cu" "F.Paste" "F.Mask")
      (net 1 "GND") (pinfunction "E") (pintype "passive"))
    (pad "3" smd rect (at 0.925 0 90) (size 0.55 0.6) (layers "F.Cu" "F.Paste" "F.Mask")
      (net 88 "/Power/DCDC_EN") (pinfunction "C") (pintype "passive"))
  )
	(footprint "antmicro-footprints:Fiducial_1mm_Mask3mm" (layer "F.Cu")
    (at 168 59)
    (descr "Circular Fiducial, 1.5mm bare copper, 3mm soldermask opening")
    (tags "fiducial")
    (property "Author" "Antmicro")
    (property "License" "Apache-2.0")
    (property "Sheetfile" "thunderbolt-pcie-adapter.kicad_sch")
    (property "Sheetname" "")
    (property "exclude_from_bom" "")
    (property "ki_description" "Fiducial mask")
    (attr through_hole exclude_from_bom)
    (fp_text reference "FID3" (at -1.122 2.595) (layer "F.SilkS")
        (effects (font (size 0.7 0.7) (thickness 0.15)) (justify left bottom))
    )
    (fp_text value "Fiducial_1mm_Mask3mm" (at 0 2.603) (layer "F.Fab")
        (effects (font (size 0.7 0.7) (thickness 0.15)) (justify left bottom))
    )
    (fp_text user "License: Apache-2.0" (at -1.25 7.003) (layer "F.Fab") hide
        (effects (font (size 0.7 0.7) (thickness 0.15)) (justify left bottom))
    )
    (fp_text user "${REFERENCE}" (at -1.25 4.603) (layer "F.Fab") hide
        (effects (font (size 0.7 0.7) (thickness 0.15)) (justify left bottom))
    )
    (fp_text user "Author: Antmicro" (at -1.25 5.803) (layer "F.Fab") hide
        (effects (font (size 0.7 0.7) (thickness 0.15)) (justify left bottom))
    )
    (fp_circle (center 0 0) (end 1.5 0)
      (stroke (width 0.05) (type solid)) (fill none) (layer "F.CrtYd"))
    (fp_circle (center 0 0) (end 1.5 0)
      (stroke (width 0.15) (type solid)) (fill none) (layer "F.Fab"))
    (pad "" smd circle (at 0 0) (size 1 1) (layers "F.Cu" "F.Mask")
      (solder_mask_margin 1) (clearance 1))
  )
	(footprint "antmicro-footprints:TP_SMD_1mm" (layer "F.Cu")
    (at 146.5 66 180)
    (property "Author" "Antmicro")
    (property "License" "Apache-2.0")
    (property "MPN" "")
    (property "Manufacturer" "")
    (property "Sheetfile" "tb-power.kicad_sch")
    (property "Sheetname" "Thunderbolt Controller - Power")
    (property "exclude_from_bom" "")
    (property "ki_description" "Test point 1mm SMD")
    (property "ki_keywords" "TESTPOINT")
    (attr exclude_from_pos_files exclude_from_bom)
    (fp_text reference "TP9" (at -0.566 -0.421 180) (layer "F.SilkS")
        (effects (font (size 0.7 0.7) (thickness 0.15)) (justify left bottom))
    )
    (fp_text value "TP_1mm_SMD" (at 0 1.4 180) (layer "F.Fab")
        (effects (font (size 0.7 0.7) (thickness 0.15)) (justify left bottom))
    )
    (fp_text user "License: Apache-2.0" (at -0.5 5.2 180) (layer "F.Fab") hide
        (effects (font (size 0.7 0.7) (thickness 0.15)) (justify left bottom))
    )
    (fp_text user "${REFERENCE}" (at -0.5 2.8 180) (layer "F.Fab") hide
        (effects (font (size 0.7 0.7) (thickness 0.15)) (justify left bottom))
    )
    (fp_text user "Author: Antmicro" (at -0.5 4 180) (layer "F.Fab") hide
        (effects (font (size 0.7 0.7) (thickness 0.15)) (justify left bottom))
    )
    (fp_circle (center 0 0) (end 0.6 0)
      (stroke (width 0.05) (type default)) (fill none) (layer "F.CrtYd"))
    (pad "1" smd circle (at 0 0 180) (size 1 1) (layers "F.Cu" "F.Mask")
      (net 112 "Net-(U4A-VCC0P9_SVR_SENSE)") (pinfunction "1") (pintype "passive"))
  )
	(footprint "antmicro-footprints:TSSOP-8_3x4.4mm_P0.65mm" (layer "F.Cu")
    (at 123 81.9 -90)
    (property "Author" "Antmicro")
    (property "License" "Apache-2.0")
    (property "MPN" "SI52112-B6-GT")
    (property "Manufacturer" "Skyworks Solutions")
    (property "Sheetfile" "tb.kicad_sch")
    (property "Sheetname" "TB Controller")
    (property "ki_description" "Clock Generator, 100MHz, 2.97V to 3.63V, 2 Outputs, TSSOP-8")
    (property "ki_keywords" "IC")
    (attr smd)
    (fp_text reference "U6" (at -1.763 -2.73 -90) (layer "F.SilkS")
        (effects (font (size 0.7 0.7) (thickness 0.15)) (justify left bottom))
    )
    (fp_text value "SI52112-B6-GT" (at 0 3 -90) (layer "F.Fab")
        (effects (font (size 0.7 0.7) (thickness 0.15)) (justify left bottom))
    )
    (fp_text user "Author: Antmicro" (at -3.55 5 -90) (layer "F.Fab") hide
        (effects (font (size 0.7 0.7) (thickness 0.15)) (justify left bottom))
    )
    (fp_text user "License: Apache-2.0" (at -3.55 6.2 -90) (layer "F.Fab") hide
        (effects (font (size 0.7 0.7) (thickness 0.15)) (justify left bottom))
    )
    (fp_text user "${REFERENCE}" (at -3.55 7.4 -90) (layer "F.Fab") hide
        (effects (font (size 0.7 0.7) (thickness 0.15)) (justify left bottom))
    )
    (fp_line (start -2.3 -1.6) (end -1.7 -1.6)
      (stroke (width 0.15) (type solid)) (layer "F.SilkS"))
    (fp_line (start -2.3 -1.3) (end -2.3 -1.6)
      (stroke (width 0.15) (type solid)) (layer "F.SilkS"))
    (fp_line (start -2.3 1.3) (end -2.3 1.6)
      (stroke (width 0.15) (type solid)) (layer "F.SilkS"))
    (fp_line (start -2.3 1.6) (end -1.7 1.6)
      (stroke (width 0.15) (type solid)) (layer "F.SilkS"))
    (fp_line (start 2.3 -1.6) (end 1.8 -1.6)
      (stroke (width 0.15) (type solid)) (layer "F.SilkS"))
    (fp_line (start 2.3 -1.3) (end 2.3 -1.6)
      (stroke (width 0.15) (type solid)) (layer "F.SilkS"))
    (fp_line (start 2.3 1.25) (end 2.3 1.6)
      (stroke (width 0.15) (type solid)) (layer "F.SilkS"))
    (fp_line (start 2.3 1.6) (end 1.8 1.6)
      (stroke (width 0.15) (type solid)) (layer "F.SilkS"))
    (fp_circle (center -2.7 -1.51) (end -2.65 -1.51)
      (stroke (width 0.15) (type solid)) (fill solid) (layer "F.SilkS"))
    (fp_rect (start -3.45 -1.75) (end 3.45 1.75)
      (stroke (width 0.05) (type solid)) (fill none) (layer "F.CrtYd"))
    (fp_line (start -2.2 -0.7) (end -2.2 1.5)
      (stroke (width 0.15) (type solid)) (layer "F.Fab"))
    (fp_line (start -2.2 -0.7) (end -1.4 -1.5)
      (stroke (width 0.15) (type solid)) (layer "F.Fab"))
    (fp_line (start -2.2 1.5) (end 2.2 1.5)
      (stroke (width 0.15) (type solid)) (layer "F.Fab"))
    (fp_line (start -1.4 -1.5) (end 2.2 -1.5)
      (stroke (width 0.15) (type solid)) (layer "F.Fab"))
    (fp_line (start 2.2 -1.5) (end 2.2 1.5)
      (stroke (width 0.15) (type solid)) (layer "F.Fab"))
    (pad "1" smd rect (at -2.7 -0.975 270) (size 1.2 0.4) (layers "F.Cu" "F.Paste" "F.Mask")
      (net 2 "3V3_SYS") (pinfunction "VDD") (pintype "power_in"))
    (pad "2" smd rect (at -2.7 -0.325 270) (size 1.2 0.4) (layers "F.Cu" "F.Paste" "F.Mask")
      (net 115 "Net-(U6-XOUT)") (pinfunction "XOUT") (pintype "output"))
    (pad "3" smd rect (at -2.7 0.325 270) (size 1.2 0.4) (layers "F.Cu" "F.Paste" "F.Mask")
      (net 116 "Net-(U6-XIN{slash}CLKIN)") (pinfunction "XIN/CLKIN") (pintype "input"))
    (pad "4" smd rect (at -2.7 0.975 270) (size 1.2 0.4) (layers "F.Cu" "F.Paste" "F.Mask")
      (net 1 "GND") (pinfunction "GND") (pintype "power_in"))
    (pad "5" smd rect (at 2.7 0.975 270) (size 1.2 0.4) (layers "F.Cu" "F.Paste" "F.Mask")
      (net 44 "PCIE_CLK_CON_P") (pinfunction "DIFF1") (pintype "output"))
    (pad "6" smd rect (at 2.7 0.325 270) (size 1.2 0.4) (layers "F.Cu" "F.Paste" "F.Mask")
      (net 45 "PCIE_CLK_CON_N") (pinfunction "~{DIFF1}") (pintype "output"))
    (pad "7" smd rect (at 2.7 -0.325 270) (size 1.2 0.4) (layers "F.Cu" "F.Paste" "F.Mask")
      (net 72 "/TB Controller/PCIE_CLK_JHL_P") (pinfunction "DIFF2") (pintype "output"))
    (pad "8" smd rect (at 2.7 -0.975 270) (size 1.2 0.4) (layers "F.Cu" "F.Paste" "F.Mask")
      (net 73 "/TB Controller/PCIE_CLK_JHL_N") (pinfunction "~{DIFF2}") (pintype "output"))
  )
)
